(kicad_pcb
	(version 20260206)
	(generator "pcbnew")
	(generator_version "10.0")
	(general
		(thickness 1.6)
		(legacy_teardrops no)
	)
	(paper "A4")
	(title_block
		(title "fcb — Lightning_FCB_BRD.brd")
		(comment 1 "Lightning (Wiwynn / Facebook NVMe JBOF) / footprints 310-313 of 495")
	)
	(layers
		(0 "F.Cu" signal "TOP")
		(4 "In1.Cu" signal "L2GND")
		(6 "In2.Cu" signal "L3VCC")
		(2 "B.Cu" signal "BOTTOM")
		(9 "F.Adhes" user "F.Adhesive")
		(11 "B.Adhes" user "B.Adhesive")
		(13 "F.Paste" user "Package Geometry/Pastemask Top")
		(15 "B.Paste" user "Package Geometry/Pastemask Bottom")
		(5 "F.SilkS" user "Ref Des/Silkscreen Top")
		(7 "B.SilkS" user "Ref Des/Silkscreen Bottom")
		(1 "F.Mask" user "Board Geometry/Soldermask Top")
		(3 "B.Mask" user "Board Geometry/Soldermask Bottom")
		(17 "Dwgs.User" user "User.Drawings")
		(19 "Cmts.User" user "User.Comments")
		(21 "Eco1.User" user "User.Eco1")
		(23 "Eco2.User" user "User.Eco2")
		(25 "Edge.Cuts" user "Board Geometry/Outline")
		(27 "Margin" user)
		(31 "F.CrtYd" user "Package Geometry/Place Bound Top")
		(29 "B.CrtYd" user "Package Geometry/Place Bound Bottom")
		(35 "F.Fab" user "Ref Des/Assembly Top")
		(33 "B.Fab" user "Ref Des/Assembly Bottom")
	)
	(footprint ""
		(layer "F.Cu")
		(at 45.500036 -294.999918)
		(property "Reference" "H6"
			(at 0 0 0)
			(layer "F.SilkS")
			(hide yes)
			(effects
				(font
					(size 1.27 1.27)
				)
			)
		)
		(property "Value" "HOLE315R138"
			(at 0 -7.0612 0)
			(unlocked yes)
			(layer "F.Fab")
			(hide yes)
			(effects
				(font
					(size 1.016 1.016)
					(thickness 0.1524)
				)
			)
		)
		(property "Device Type" "HOLE315R138"
			(at 0 -8.5852 0)
			(unlocked yes)
			(layer "F.Fab")
			(hide yes)
			(effects
				(font
					(size 1.016 1.016)
					(thickness 0.1524)
				)
			)
		)
		(duplicate_pad_numbers_are_jumpers no)
		(fp_poly
			(pts
				(xy 0 4.3053) (xy -0.13462 4.30276) (xy -0.27051 4.29641) (xy -0.40513 4.28625) (xy -0.53975 4.27101)
				(xy -0.6731 4.25196) (xy -0.80645 4.2291) (xy -0.9398 4.20116) (xy -1.07061 4.17068) (xy -1.20142 4.13385)
				(xy -1.33096 4.09448) (xy -1.45796 4.0513) (xy -1.58496 4.00304) (xy -1.70942 3.95097) (xy -1.83261 3.89509)
				(xy -1.95453 3.83667) (xy -2.07391 3.77317) (xy -2.19202 3.70586) (xy -2.30632 3.63474) (xy -2.41935 3.56108)
				(xy -2.53111 3.48361) (xy -2.63906 3.40233) (xy -2.74447 3.31724) (xy -2.84734 3.22961) (xy -2.94767 3.13817)
				(xy -3.04419 3.04419) (xy -3.13817 2.94767) (xy -3.22961 2.84734) (xy -3.31724 2.74447) (xy -3.40233 2.63906)
				(xy -3.48361 2.53111) (xy -3.56108 2.41935) (xy -3.63474 2.30632) (xy -3.70586 2.19202) (xy -3.77317 2.07391)
				(xy -3.83667 1.95453) (xy -3.89509 1.83261) (xy -3.95097 1.70942) (xy -4.00304 1.58496) (xy -4.0513 1.45796)
				(xy -4.09448 1.33096) (xy -4.13385 1.20142) (xy -4.17068 1.07061) (xy -4.20116 0.9398) (xy -4.2291 0.80645)
				(xy -4.25196 0.6731) (xy -4.27101 0.53975) (xy -4.28625 0.40513) (xy -4.29641 0.27051) (xy -4.30276 0.13462)
				(xy -4.3053 0) (xy -4.30276 -0.13462) (xy -4.29641 -0.27051) (xy -4.28625 -0.40513) (xy -4.27101 -0.53975)
				(xy -4.25196 -0.6731) (xy -4.2291 -0.80645) (xy -4.20116 -0.9398) (xy -4.17068 -1.07061) (xy -4.13385 -1.20142)
				(xy -4.09448 -1.33096) (xy -4.0513 -1.45796) (xy -4.00304 -1.58496) (xy -3.95097 -1.70942) (xy -3.89509 -1.83261)
				(xy -3.83667 -1.95453) (xy -3.77317 -2.07391) (xy -3.70586 -2.19202) (xy -3.63474 -2.30632) (xy -3.56108 -2.41935)
				(xy -3.48361 -2.53111) (xy -3.40233 -2.63906) (xy -3.31724 -2.74447) (xy -3.22961 -2.84734) (xy -3.13817 -2.94767)
				(xy -3.04419 -3.04419) (xy -2.94767 -3.13817) (xy -2.84734 -3.22961) (xy -2.74447 -3.31724) (xy -2.63906 -3.40233)
				(xy -2.53111 -3.48361) (xy -2.41935 -3.56108) (xy -2.30632 -3.63474) (xy -2.19202 -3.70586) (xy -2.07391 -3.77317)
				(xy -1.95453 -3.83667) (xy -1.83261 -3.89509) (xy -1.70942 -3.95097) (xy -1.58496 -4.00304) (xy -1.45796 -4.0513)
				(xy -1.33096 -4.09448) (xy -1.20142 -4.13385) (xy -1.07061 -4.17068) (xy -0.9398 -4.20116) (xy -0.80645 -4.2291)
				(xy -0.6731 -4.25196) (xy -0.53975 -4.27101) (xy -0.40513 -4.28625) (xy -0.27051 -4.29641) (xy -0.13462 -4.30276)
				(xy 0 -4.3053) (xy 0.13462 -4.30276) (xy 0.27051 -4.29641) (xy 0.40513 -4.28625) (xy 0.53975 -4.27101)
				(xy 0.6731 -4.25196) (xy 0.80645 -4.2291) (xy 0.9398 -4.20116) (xy 1.07061 -4.17068) (xy 1.20142 -4.13385)
				(xy 1.33096 -4.09448) (xy 1.45796 -4.0513) (xy 1.58496 -4.00304) (xy 1.70942 -3.95097) (xy 1.83261 -3.89509)
				(xy 1.95453 -3.83667) (xy 2.07391 -3.77317) (xy 2.19202 -3.70586) (xy 2.30632 -3.63474) (xy 2.41935 -3.56108)
				(xy 2.53111 -3.48361) (xy 2.63906 -3.40233) (xy 2.74447 -3.31724) (xy 2.84734 -3.22961) (xy 2.94767 -3.13817)
				(xy 3.04419 -3.04419) (xy 3.13817 -2.94767) (xy 3.22961 -2.84734) (xy 3.31724 -2.74447) (xy 3.40233 -2.63906)
				(xy 3.48361 -2.53111) (xy 3.56108 -2.41935) (xy 3.63474 -2.30632) (xy 3.70586 -2.19202) (xy 3.77317 -2.07391)
				(xy 3.83667 -1.95453) (xy 3.89509 -1.83261) (xy 3.95097 -1.70942) (xy 4.00304 -1.58496) (xy 4.0513 -1.45796)
				(xy 4.09448 -1.33096) (xy 4.13385 -1.20142) (xy 4.17068 -1.07061) (xy 4.20116 -0.9398) (xy 4.2291 -0.80645)
				(xy 4.25196 -0.6731) (xy 4.27101 -0.53975) (xy 4.28625 -0.40513) (xy 4.29641 -0.27051) (xy 4.30276 -0.13462)
				(xy 4.3053 0) (xy 4.30276 0.13462) (xy 4.29641 0.27051) (xy 4.28625 0.40513) (xy 4.27101 0.53975)
				(xy 4.25196 0.6731) (xy 4.2291 0.80645) (xy 4.20116 0.9398) (xy 4.17068 1.07061) (xy 4.13385 1.20142)
				(xy 4.09448 1.33096) (xy 4.0513 1.45796) (xy 4.00304 1.58496) (xy 3.95097 1.70942) (xy 3.89509 1.83261)
				(xy 3.83667 1.95453) (xy 3.77317 2.07391) (xy 3.70586 2.19202) (xy 3.63474 2.30632) (xy 3.56108 2.41935)
				(xy 3.48361 2.53111) (xy 3.40233 2.63906) (xy 3.31724 2.74447) (xy 3.22961 2.84734) (xy 3.13817 2.94767)
				(xy 3.04419 3.04419) (xy 2.94767 3.13817) (xy 2.84734 3.22961) (xy 2.74447 3.31724) (xy 2.63906 3.40233)
				(xy 2.53111 3.48361) (xy 2.41935 3.56108) (xy 2.30632 3.63474) (xy 2.19202 3.70586) (xy 2.07391 3.77317)
				(xy 1.95453 3.83667) (xy 1.83261 3.89509) (xy 1.70942 3.95097) (xy 1.58496 4.00304) (xy 1.45796 4.0513)
				(xy 1.33096 4.09448) (xy 1.20142 4.13385) (xy 1.07061 4.17068) (xy 0.9398 4.20116) (xy 0.80645 4.2291)
				(xy 0.6731 4.25196) (xy 0.53975 4.27101) (xy 0.40513 4.28625) (xy 0.27051 4.29641) (xy 0.13462 4.30276)
			)
			(stroke
				(width 0)
				(type default)
			)
			(fill no)
			(layer "F.CrtYd")
		)
		(fp_poly
			(pts
				(xy 0 4.3053) (xy -0.13462 4.30276) (xy -0.27051 4.29641) (xy -0.40513 4.28625) (xy -0.53975 4.27101)
				(xy -0.6731 4.25196) (xy -0.80645 4.2291) (xy -0.9398 4.20116) (xy -1.07061 4.17068) (xy -1.20142 4.13385)
				(xy -1.33096 4.09448) (xy -1.45796 4.0513) (xy -1.58496 4.00304) (xy -1.70942 3.95097) (xy -1.83261 3.89509)
				(xy -1.95453 3.83667) (xy -2.07391 3.77317) (xy -2.19202 3.70586) (xy -2.30632 3.63474) (xy -2.41935 3.56108)
				(xy -2.53111 3.48361) (xy -2.63906 3.40233) (xy -2.74447 3.31724) (xy -2.84734 3.22961) (xy -2.94767 3.13817)
				(xy -3.04419 3.04419) (xy -3.13817 2.94767) (xy -3.22961 2.84734) (xy -3.31724 2.74447) (xy -3.40233 2.63906)
				(xy -3.48361 2.53111) (xy -3.56108 2.41935) (xy -3.63474 2.30632) (xy -3.70586 2.19202) (xy -3.77317 2.07391)
				(xy -3.83667 1.95453) (xy -3.89509 1.83261) (xy -3.95097 1.70942) (xy -4.00304 1.58496) (xy -4.0513 1.45796)
				(xy -4.09448 1.33096) (xy -4.13385 1.20142) (xy -4.17068 1.07061) (xy -4.20116 0.9398) (xy -4.2291 0.80645)
				(xy -4.25196 0.6731) (xy -4.27101 0.53975) (xy -4.28625 0.40513) (xy -4.29641 0.27051) (xy -4.30276 0.13462)
				(xy -4.3053 0) (xy -4.30276 -0.13462) (xy -4.29641 -0.27051) (xy -4.28625 -0.40513) (xy -4.27101 -0.53975)
				(xy -4.25196 -0.6731) (xy -4.2291 -0.80645) (xy -4.20116 -0.9398) (xy -4.17068 -1.07061) (xy -4.13385 -1.20142)
				(xy -4.09448 -1.33096) (xy -4.0513 -1.45796) (xy -4.00304 -1.58496) (xy -3.95097 -1.70942) (xy -3.89509 -1.83261)
				(xy -3.83667 -1.95453) (xy -3.77317 -2.07391) (xy -3.70586 -2.19202) (xy -3.63474 -2.30632) (xy -3.56108 -2.41935)
				(xy -3.48361 -2.53111) (xy -3.40233 -2.63906) (xy -3.31724 -2.74447) (xy -3.22961 -2.84734) (xy -3.13817 -2.94767)
				(xy -3.04419 -3.04419) (xy -2.94767 -3.13817) (xy -2.84734 -3.22961) (xy -2.74447 -3.31724) (xy -2.63906 -3.40233)
				(xy -2.53111 -3.48361) (xy -2.41935 -3.56108) (xy -2.30632 -3.63474) (xy -2.19202 -3.70586) (xy -2.07391 -3.77317)
				(xy -1.95453 -3.83667) (xy -1.83261 -3.89509) (xy -1.70942 -3.95097) (xy -1.58496 -4.00304) (xy -1.45796 -4.0513)
				(xy -1.33096 -4.09448) (xy -1.20142 -4.13385) (xy -1.07061 -4.17068) (xy -0.9398 -4.20116) (xy -0.80645 -4.2291)
				(xy -0.6731 -4.25196) (xy -0.53975 -4.27101) (xy -0.40513 -4.28625) (xy -0.27051 -4.29641) (xy -0.13462 -4.30276)
				(xy 0 -4.3053) (xy 0.13462 -4.30276) (xy 0.27051 -4.29641) (xy 0.40513 -4.28625) (xy 0.53975 -4.27101)
				(xy 0.6731 -4.25196) (xy 0.80645 -4.2291) (xy 0.9398 -4.20116) (xy 1.07061 -4.17068) (xy 1.20142 -4.13385)
				(xy 1.33096 -4.09448) (xy 1.45796 -4.0513) (xy 1.58496 -4.00304) (xy 1.70942 -3.95097) (xy 1.83261 -3.89509)
				(xy 1.95453 -3.83667) (xy 2.07391 -3.77317) (xy 2.19202 -3.70586) (xy 2.30632 -3.63474) (xy 2.41935 -3.56108)
				(xy 2.53111 -3.48361) (xy 2.63906 -3.40233) (xy 2.74447 -3.31724) (xy 2.84734 -3.22961) (xy 2.94767 -3.13817)
				(xy 3.04419 -3.04419) (xy 3.13817 -2.94767) (xy 3.22961 -2.84734) (xy 3.31724 -2.74447) (xy 3.40233 -2.63906)
				(xy 3.48361 -2.53111) (xy 3.56108 -2.41935) (xy 3.63474 -2.30632) (xy 3.70586 -2.19202) (xy 3.77317 -2.07391)
				(xy 3.83667 -1.95453) (xy 3.89509 -1.83261) (xy 3.95097 -1.70942) (xy 4.00304 -1.58496) (xy 4.0513 -1.45796)
				(xy 4.09448 -1.33096) (xy 4.13385 -1.20142) (xy 4.17068 -1.07061) (xy 4.20116 -0.9398) (xy 4.2291 -0.80645)
				(xy 4.25196 -0.6731) (xy 4.27101 -0.53975) (xy 4.28625 -0.40513) (xy 4.29641 -0.27051) (xy 4.30276 -0.13462)
				(xy 4.3053 0) (xy 4.30276 0.13462) (xy 4.29641 0.27051) (xy 4.28625 0.40513) (xy 4.27101 0.53975)
				(xy 4.25196 0.6731) (xy 4.2291 0.80645) (xy 4.20116 0.9398) (xy 4.17068 1.07061) (xy 4.13385 1.20142)
				(xy 4.09448 1.33096) (xy 4.0513 1.45796) (xy 4.00304 1.58496) (xy 3.95097 1.70942) (xy 3.89509 1.83261)
				(xy 3.83667 1.95453) (xy 3.77317 2.07391) (xy 3.70586 2.19202) (xy 3.63474 2.30632) (xy 3.56108 2.41935)
				(xy 3.48361 2.53111) (xy 3.40233 2.63906) (xy 3.31724 2.74447) (xy 3.22961 2.84734) (xy 3.13817 2.94767)
				(xy 3.04419 3.04419) (xy 2.94767 3.13817) (xy 2.84734 3.22961) (xy 2.74447 3.31724) (xy 2.63906 3.40233)
				(xy 2.53111 3.48361) (xy 2.41935 3.56108) (xy 2.30632 3.63474) (xy 2.19202 3.70586) (xy 2.07391 3.77317)
				(xy 1.95453 3.83667) (xy 1.83261 3.89509) (xy 1.70942 3.95097) (xy 1.58496 4.00304) (xy 1.45796 4.0513)
				(xy 1.33096 4.09448) (xy 1.20142 4.13385) (xy 1.07061 4.17068) (xy 0.9398 4.20116) (xy 0.80645 4.2291)
				(xy 0.6731 4.25196) (xy 0.53975 4.27101) (xy 0.40513 4.28625) (xy 0.27051 4.29641) (xy 0.13462 4.30276)
			)
			(stroke
				(width 0)
				(type default)
			)
			(fill no)
			(layer "F.Fab")
		)
		(pad "1" thru_hole circle
			(at 0 0)
			(size 8.001 8.001)
			(drill 3.5052)
			(layers "*.Cu" "*.Mask")
			(remove_unused_layers no)
			(net "GND")
			(clearance -1.7399)
			(thermal_gap 0.3048)
			(padstack
				(mode front_inner_back)
				(layer "Inner"
					(shape circle)
					(size 3.9116 3.9116)
					(clearance 0.3048)
				)
				(layer "B.Cu"
					(shape circle)
					(size 8.001 8.001)
					(clearance -1.7399)
				)
			)
		)
	)
	(footprint ""
		(layer "F.Cu")
		(at 18.1356 -17.768316)
		(property "Reference" "C27"
			(at 0 0 0)
			(layer "F.SilkS")
			(hide yes)
			(effects
				(font
					(size 1.27 1.27)
				)
			)
		)
		(property "Value" "SCD1U16V2KX-3GP"
			(at 1.1811 -2.7051 0)
			(unlocked yes)
			(layer "F.Fab")
			(hide yes)
			(effects
				(font
					(size 1.016 1.016)
					(thickness 0.1524)
				)
			)
		)
		(property "Device Type" "C402H22"
			(at 1.1811 -4.2291 0)
			(unlocked yes)
			(layer "F.Fab")
			(hide yes)
			(effects
				(font
					(size 1.016 1.016)
					(thickness 0.1524)
				)
			)
		)
		(duplicate_pad_numbers_are_jumpers no)
		(fp_rect
			(start -0.4318 0.9525)
			(end 0.4318 -0.9525)
			(stroke
				(width 0)
				(type default)
			)
			(fill no)
			(layer "F.CrtYd")
		)
		(fp_rect
			(start -0.4318 0.9525)
			(end 0.4318 -0.9525)
			(stroke
				(width 0)
				(type default)
			)
			(fill no)
			(layer "F.Fab")
		)
		(pad "1" smd custom
			(at 0 -0.4445)
			(size 0.1524 0.1524)
			(layers "F.Cu" "F.Mask" "F.Paste")
			(net "FAN_TACH12")
			(options
				(clearance outline)
				(anchor circle)
			)
			(primitives
				(gr_poly
					(pts
						(arc
							(start 0.3048 -0.2032)
							(mid 0.275042 -0.275042)
							(end 0.2032 -0.3048)
						)
						(arc
							(start -0.2032 -0.3048)
							(mid -0.275042 -0.275042)
							(end -0.3048 -0.2032)
						)
						(arc
							(start -0.3048 0.2032)
							(mid -0.275042 0.275042)
							(end -0.2032 0.3048)
						)
						(arc
							(start 0.2032 0.3048)
							(mid 0.275042 0.275042)
							(end 0.3048 0.2032)
						)
					)
					(width 0)
					(fill yes)
				)
			)
		)
		(pad "2" smd custom
			(at 0 0.4445)
			(size 0.1524 0.1524)
			(layers "F.Cu" "F.Mask" "F.Paste")
			(net "GND")
			(options
				(clearance outline)
				(anchor circle)
			)
			(primitives
				(gr_poly
					(pts
						(arc
							(start 0.3048 -0.2032)
							(mid 0.275042 -0.275042)
							(end 0.2032 -0.3048)
						)
						(arc
							(start -0.2032 -0.3048)
							(mid -0.275042 -0.275042)
							(end -0.3048 -0.2032)
						)
						(arc
							(start -0.3048 0.2032)
							(mid -0.275042 0.275042)
							(end -0.2032 0.3048)
						)
						(arc
							(start 0.2032 0.3048)
							(mid 0.275042 0.275042)
							(end 0.3048 0.2032)
						)
					)
					(width 0)
					(fill yes)
				)
			)
		)
	)
	(footprint ""
		(layer "F.Cu")
		(at 7.8232 -83.439 90)
		(property "Reference" "R123"
			(at 0 0 90)
			(layer "F.SilkS")
			(hide yes)
			(effects
				(font
					(size 1.27 1.27)
				)
			)
		)
		(property "Value" "1K8R6J-GP"
			(at -0.0508 -4.8514 90)
			(unlocked yes)
			(layer "F.Fab")
			(hide yes)
			(effects
				(font
					(size 1.016 1.016)
					(thickness 0.1524)
				)
			)
		)
		(property "Device Type" "R1206H28"
			(at 0 -6.3754 90)
			(unlocked yes)
			(layer "F.Fab")
			(hide yes)
			(effects
				(font
					(size 1.016 1.016)
					(thickness 0.1524)
				)
			)
		)
		(duplicate_pad_numbers_are_jumpers no)
		(fp_line
			(start 1.016 -2.2352)
			(end 1.016 2.2352)
			(stroke
				(width 0.1524)
				(type default)
			)
			(layer "F.SilkS")
		)
		(fp_line
			(start -1.016 -2.2352)
			(end 1.016 -2.2352)
			(stroke
				(width 0.1524)
				(type default)
			)
			(layer "F.SilkS")
		)
		(fp_line
			(start 1.016 2.2352)
			(end -1.016 2.2352)
			(stroke
				(width 0.1524)
				(type default)
			)
			(layer "F.SilkS")
		)
		(fp_line
			(start -1.016 2.2352)
			(end -1.016 -2.2352)
			(stroke
				(width 0.1524)
				(type default)
			)
			(layer "F.SilkS")
		)
		(fp_rect
			(start -1.0922 2.3114)
			(end 1.0922 -2.3114)
			(stroke
				(width 0)
				(type default)
			)
			(fill no)
			(layer "F.CrtYd")
		)
		(fp_poly
			(pts
				(xy -1.0922 -2.3114) (xy 1.0922 -2.3114) (xy 1.0922 2.3114) (xy -1.0922 2.3114)
			)
			(stroke
				(width 0)
				(type default)
			)
			(fill no)
			(layer "F.Fab")
		)
		(pad "1" smd rect
			(at 0 -1.397 90)
			(size 1.651 1.27)
			(layers "F.Cu" "F.Mask" "F.Paste")
			(net "P12V")
		)
		(pad "2" smd rect
			(at 0 1.397 90)
			(size 1.651 1.27)
			(layers "F.Cu" "F.Mask" "F.Paste")
			(net "LED_DR_LED4_BLUE")
		)
	)
	(footprint ""
		(layer "F.Cu")
		(at 37.2618 -121.793)
		(property "Reference" "C257"
			(at 0 0 0)
			(layer "F.SilkS")
			(hide yes)
			(effects
				(font
					(size 1.27 1.27)
				)
			)
		)
		(property "Value" "SC1U25V3KX-1-GP"
			(at 0 -2.8194 0)
			(unlocked yes)
			(layer "F.Fab")
			(hide yes)
			(effects
				(font
					(size 1.016 1.016)
					(thickness 0.1524)
				)
			)
		)
		(property "Device Type" "C603H36"
			(at 0 -4.3434 0)
			(unlocked yes)
			(layer "F.Fab")
			(hide yes)
			(effects
				(font
					(size 1.016 1.016)
					(thickness 0.1524)
				)
			)
		)
		(duplicate_pad_numbers_are_jumpers no)
		(fp_line
			(start 0.508 0)
			(end -0.508 0)
			(stroke
				(width 0.2032)
				(type default)
			)
			(layer "F.SilkS")
		)
		(fp_rect
			(start -0.5842 1.3335)
			(end 0.5842 -1.3335)
			(stroke
				(width 0)
				(type default)
			)
			(fill no)
			(layer "F.CrtYd")
		)
		(fp_rect
			(start -0.5842 1.3335)
			(end 0.5842 -1.3335)
			(stroke
				(width 0)
				(type default)
			)
			(fill no)
			(layer "F.Fab")
		)
		(pad "1" smd custom
			(at 0 -0.762)
			(size 0.2159 0.2159)
			(layers "F.Cu" "F.Mask" "F.Paste")
			(net "P12V")
			(options
				(clearance outline)
				(anchor circle)
			)
			(primitives
				(gr_poly
					(pts
						(arc
							(start -0.3302 -0.4318)
							(mid -0.402042 -0.402042)
							(end -0.4318 -0.3302)
						)
						(arc
							(start -0.4318 0.3302)
							(mid -0.402042 0.402042)
							(end -0.3302 0.4318)
						)
						(arc
							(start 0.3302 0.4318)
							(mid 0.402042 0.402042)
							(end 0.4318 0.3302)
						)
						(arc
							(start 0.4318 -0.3302)
							(mid 0.402042 -0.402042)
							(end 0.3302 -0.4318)
						)
					)
					(width 0)
					(fill yes)
				)
			)
		)
		(pad "2" smd custom
			(at 0 0.762)
			(size 0.2159 0.2159)
			(layers "F.Cu" "F.Mask" "F.Paste")
			(net "GND")
			(options
				(clearance outline)
				(anchor circle)
			)
			(primitives
				(gr_poly
					(pts
						(arc
							(start -0.3302 -0.4318)
							(mid -0.402042 -0.402042)
							(end -0.4318 -0.3302)
						)
						(arc
							(start -0.4318 0.3302)
							(mid -0.402042 0.402042)
							(end -0.3302 0.4318)
						)
						(arc
							(start 0.3302 0.4318)
							(mid 0.402042 0.402042)
							(end 0.4318 0.3302)
						)
						(arc
							(start 0.4318 -0.3302)
							(mid 0.402042 -0.402042)
							(end 0.3302 -0.4318)
						)
					)
					(width 0)
					(fill yes)
				)
			)
		)
	)
)
